# S9S_MB_2U (Grand Teton) — schematic netlist excerpt (pin names and nets, part order shuffled) for the footprints in the layout excerpt that follows; sources: Cadence DE-HDL packaged netlist, KiCad conversion of 03242023_DA0F0TMBIJ0_F0T_Motherboard_J_brd_V01_OCP.brd

C615  Q_CAP  1UF 25V 10% EMPTY  pkg C0402  page 130 : A = RST_PLD_CPU1_DRAM_CD_N ; B = GND
R3167  Q_RES  4.7K 1% CHIP  pkg 0402LF  page 159 : A = OCP_V3_2_ID1 ; B = GND
C381  Q_CAP  47UF 4V 20% X6S  pkg C0805  page 75 : A = PVCCIN_CPU0 ; B = GND

(kicad_pcb
	(version 20260206)
	(generator "pcbnew")
	(generator_version "10.0")
	(general
		(thickness 1.6)
		(legacy_teardrops no)
	)
	(paper "A4")
	(title_block
		(title "03242023_DA0F0TMBIJ0_F0T_Motherboard_J_brd_V01_OCP.brd")
		(comment 1 "Grand Teton / footprints 4349-4351 of 6105")
	)
	(layers
		(0 "F.Cu" signal "TOP")
		(4 "In1.Cu" signal "GND")
		(6 "In2.Cu" signal "IN1")
		(8 "In3.Cu" signal "GND1")
		(10 "In4.Cu" signal "IN2")
		(12 "In5.Cu" signal "GND2")
		(14 "In6.Cu" signal "IN3")
		(16 "In7.Cu" signal "GND3")
		(18 "In8.Cu" signal "VCC")
		(20 "In9.Cu" signal "VCC1")
		(22 "In10.Cu" signal "GND4")
		(24 "In11.Cu" signal "IN4")
		(26 "In12.Cu" signal "GND5")
		(28 "In13.Cu" signal "IN5")
		(30 "In14.Cu" signal "GND6")
		(32 "In15.Cu" signal "IN6")
		(34 "In16.Cu" signal "GND7")
		(2 "B.Cu" signal "BOTTOM")
		(9 "F.Adhes" user "F.Adhesive")
		(11 "B.Adhes" user "B.Adhesive")
		(13 "F.Paste" user "Package Geometry/Pastemask Top")
		(15 "B.Paste" user "Package Geometry/Pastemask Bottom")
		(5 "F.SilkS" user "Ref Des/Silkscreen Top")
		(7 "B.SilkS" user "Ref Des/Silkscreen Bottom")
		(1 "F.Mask" user "Board Geometry/Soldermask Top")
		(3 "B.Mask" user "Board Geometry/Soldermask Bottom")
		(17 "Dwgs.User" user "User.Drawings")
		(19 "Cmts.User" user "User.Comments")
		(21 "Eco1.User" user "User.Eco1")
		(23 "Eco2.User" user "User.Eco2")
		(25 "Edge.Cuts" user "Board Geometry/Outline")
		(27 "Margin" user)
		(31 "F.CrtYd" user "Package Geometry/Place Bound Top")
		(29 "B.CrtYd" user "Package Geometry/Place Bound Bottom")
		(35 "F.Fab" user "Ref Des/Assembly Top")
		(33 "B.Fab" user "Ref Des/Assembly Bottom")
	)
	(footprint ""
		(layer "B.Cu")
		(at 25.343866 -193.152776 -90)
		(property "Reference" "C615"
			(at 0 0 90)
			(layer "B.SilkS")
			(hide yes)
			(effects
				(font
					(size 1.27 1.27)
				)
				(justify mirror)
			)
		)
		(property "Value" ""
			(at 0 0 90)
			(layer "B.Fab")
			(effects
				(font
					(size 1.27 1.27)
				)
				(justify mirror)
			)
		)
		(duplicate_pad_numbers_are_jumpers no)
		(fp_line
			(start -0.7874 0.4064)
			(end 0.7874 0.4064)
			(stroke
				(width 0.1524)
				(type default)
			)
			(layer "B.SilkS")
		)
		(fp_line
			(start 0.7874 0.4064)
			(end 0.7874 -0.4064)
			(stroke
				(width 0.1524)
				(type default)
			)
			(layer "B.SilkS")
		)
		(fp_line
			(start -0.7874 -0.4064)
			(end -0.7874 0.4064)
			(stroke
				(width 0.1524)
				(type default)
			)
			(layer "B.SilkS")
		)
		(fp_line
			(start 0.7874 -0.4064)
			(end -0.7874 -0.4064)
			(stroke
				(width 0.1524)
				(type default)
			)
			(layer "B.SilkS")
		)
		(fp_line
			(start -0.67945 0.3048)
			(end -0.120396 0.3048)
			(stroke
				(width 0.1)
				(type default)
			)
			(layer "B.Fab")
		)
		(fp_line
			(start -0.120396 0.3048)
			(end -0.120396 0.2794)
			(stroke
				(width 0.1)
				(type default)
			)
			(layer "B.Fab")
		)
		(fp_line
			(start 0.12065 0.3048)
			(end 0.67945 0.3048)
			(stroke
				(width 0.1)
				(type default)
			)
			(layer "B.Fab")
		)
		(fp_line
			(start 0.67945 0.3048)
			(end 0.67945 -0.305054)
			(stroke
				(width 0.1)
				(type default)
			)
			(layer "B.Fab")
		)
		(fp_line
			(start -0.120396 0.2794)
			(end 0.12065 0.2794)
			(stroke
				(width 0.1)
				(type default)
			)
			(layer "B.Fab")
		)
		(fp_line
			(start 0.12065 0.2794)
			(end 0.12065 0.3048)
			(stroke
				(width 0.1)
				(type default)
			)
			(layer "B.Fab")
		)
		(fp_line
			(start -0.12065 -0.2794)
			(end -0.12065 -0.3048)
			(stroke
				(width 0.1)
				(type default)
			)
			(layer "B.Fab")
		)
		(fp_line
			(start 0.12065 -0.2794)
			(end -0.12065 -0.2794)
			(stroke
				(width 0.1)
				(type default)
			)
			(layer "B.Fab")
		)
		(fp_line
			(start -0.67945 -0.3048)
			(end -0.67945 0.3048)
			(stroke
				(width 0.1)
				(type default)
			)
			(layer "B.Fab")
		)
		(fp_line
			(start -0.12065 -0.3048)
			(end -0.67945 -0.3048)
			(stroke
				(width 0.1)
				(type default)
			)
			(layer "B.Fab")
		)
		(fp_line
			(start 0.12065 -0.305054)
			(end 0.12065 -0.2794)
			(stroke
				(width 0.1)
				(type default)
			)
			(layer "B.Fab")
		)
		(fp_line
			(start 0.67945 -0.305054)
			(end 0.12065 -0.305054)
			(stroke
				(width 0.1)
				(type default)
			)
			(layer "B.Fab")
		)
		(pad "1" smd circle
			(at 0.40005 0 90)
			(size 0 0)
			(layers "B.Cu" "B.Mask" "B.Paste")
			(net "RST_PLD_CPU1_DRAM_CD_N")
		)
		(pad "2" smd circle
			(at -0.40005 0 90)
			(size 0 0)
			(layers "B.Cu" "B.Mask" "B.Paste")
			(net "GND")
		)
	)
	(footprint ""
		(layer "B.Cu")
		(at 366.086898 -241.16665 -90)
		(property "Reference" "C381"
			(at 0 0 90)
			(layer "B.SilkS")
			(hide yes)
			(effects
				(font
					(size 1.27 1.27)
				)
				(justify mirror)
			)
		)
		(property "Value" ""
			(at 0 0 90)
			(layer "B.Fab")
			(effects
				(font
					(size 1.27 1.27)
				)
				(justify mirror)
			)
		)
		(duplicate_pad_numbers_are_jumpers no)
		(fp_line
			(start -1.524 0.762)
			(end 1.524 0.762)
			(stroke
				(width 0.1524)
				(type default)
			)
			(layer "B.SilkS")
		)
		(fp_line
			(start 1.524 0.762)
			(end 1.524 -0.762)
			(stroke
				(width 0.1524)
				(type default)
			)
			(layer "B.SilkS")
		)
		(fp_line
			(start -1.524 -0.762)
			(end -1.524 0.762)
			(stroke
				(width 0.1524)
				(type default)
			)
			(layer "B.SilkS")
		)
		(fp_line
			(start 1.524 -0.762)
			(end -1.524 -0.762)
			(stroke
				(width 0.1524)
				(type default)
			)
			(layer "B.SilkS")
		)
		(fp_line
			(start -1.1049 0.724916)
			(end -1.1049 -0.724916)
			(stroke
				(width 0.1)
				(type default)
			)
			(layer "B.Fab")
		)
		(fp_line
			(start 1.1049 0.724916)
			(end -1.1049 0.724916)
			(stroke
				(width 0.1)
				(type default)
			)
			(layer "B.Fab")
		)
		(fp_line
			(start -1.1049 -0.724916)
			(end 1.1049 -0.724916)
			(stroke
				(width 0.1)
				(type default)
			)
			(layer "B.Fab")
		)
		(fp_line
			(start 1.1049 -0.724916)
			(end 1.1049 0.724916)
			(stroke
				(width 0.1)
				(type default)
			)
			(layer "B.Fab")
		)
		(pad "1" smd rect
			(at 0.889 0 270)
			(size 1.016 1.27)
			(layers "B.Cu" "B.Mask" "B.Paste")
			(net "PVCCIN_CPU0")
		)
		(pad "2" smd rect
			(at -0.889 0 270)
			(size 1.016 1.27)
			(layers "B.Cu" "B.Mask" "B.Paste")
			(net "GND")
		)
	)
	(footprint ""
		(layer "B.Cu")
		(at 74.04608 -4.251198 90)
		(property "Reference" "R3167"
			(at 0 0 90)
			(layer "B.SilkS")
			(hide yes)
			(effects
				(font
					(size 1.27 1.27)
				)
				(justify mirror)
			)
		)
		(property "Value" ""
			(at 0 0 90)
			(layer "B.Fab")
			(effects
				(font
					(size 1.27 1.27)
				)
				(justify mirror)
			)
		)
		(duplicate_pad_numbers_are_jumpers no)
		(fp_line
			(start 0.7874 -0.4064)
			(end -0.7874 -0.4064)
			(stroke
				(width 0.1524)
				(type default)
			)
			(layer "B.SilkS")
		)
		(fp_line
			(start -0.7874 -0.4064)
			(end -0.7874 0.4064)
			(stroke
				(width 0.1524)
				(type default)
			)
			(layer "B.SilkS")
		)
		(fp_line
			(start 0.7874 0.4064)
			(end 0.7874 -0.4064)
			(stroke
				(width 0.1524)
				(type default)
			)
			(layer "B.SilkS")
		)
		(fp_line
			(start -0.7874 0.4064)
			(end 0.7874 0.4064)
			(stroke
				(width 0.1524)
				(type default)
			)
			(layer "B.SilkS")
		)
		(fp_line
			(start 0.67945 -0.305054)
			(end 0.12065 -0.305054)
			(stroke
				(width 0.1)
				(type default)
			)
			(layer "B.Fab")
		)
		(fp_line
			(start 0.12065 -0.305054)
			(end 0.12065 -0.2794)
			(stroke
				(width 0.1)
				(type default)
			)
			(layer "B.Fab")
		)
		(fp_line
			(start -0.12065 -0.3048)
			(end -0.67945 -0.3048)
			(stroke
				(width 0.1)
				(type default)
			)
			(layer "B.Fab")
		)
		(fp_line
			(start -0.67945 -0.3048)
			(end -0.67945 0.3048)
			(stroke
				(width 0.1)
				(type default)
			)
			(layer "B.Fab")
		)
		(fp_line
			(start 0.12065 -0.2794)
			(end -0.12065 -0.2794)
			(stroke
				(width 0.1)
				(type default)
			)
			(layer "B.Fab")
		)
		(fp_line
			(start -0.12065 -0.2794)
			(end -0.12065 -0.3048)
			(stroke
				(width 0.1)
				(type default)
			)
			(layer "B.Fab")
		)
		(fp_line
			(start 0.12065 0.2794)
			(end 0.12065 0.3048)
			(stroke
				(width 0.1)
				(type default)
			)
			(layer "B.Fab")
		)
		(fp_line
			(start -0.120396 0.2794)
			(end 0.12065 0.2794)
			(stroke
				(width 0.1)
				(type default)
			)
			(layer "B.Fab")
		)
		(fp_line
			(start 0.67945 0.3048)
			(end 0.67945 -0.305054)
			(stroke
				(width 0.1)
				(type default)
			)
			(layer "B.Fab")
		)
		(fp_line
			(start 0.12065 0.3048)
			(end 0.67945 0.3048)
			(stroke
				(width 0.1)
				(type default)
			)
			(layer "B.Fab")
		)
		(fp_line
			(start -0.120396 0.3048)
			(end -0.120396 0.2794)
			(stroke
				(width 0.1)
				(type default)
			)
			(layer "B.Fab")
		)
		(fp_line
			(start -0.67945 0.3048)
			(end -0.120396 0.3048)
			(stroke
				(width 0.1)
				(type default)
			)
			(layer "B.Fab")
		)
		(pad "1" smd circle
			(at 0.40005 0 270)
			(size 0 0)
			(layers "B.Cu" "B.Mask" "B.Paste")
			(net "OCP_V3_2_ID1")
		)
		(pad "2" smd circle
			(at -0.40005 0 270)
			(size 0 0)
			(layers "B.Cu" "B.Mask" "B.Paste")
			(net "GND")
		)
	)
)
